(kicad_pcb
	(version 20241229)
	(generator "pcbnew")
	(generator_version "9.0")
	(general
		(thickness 1.62)
		(legacy_teardrops no)
	)
	(paper "A4")
	(title_block
		(title "OCuLink to 10GbE adapter")
		(date "2026-02-23")
		(rev "1.1.0")
		(company "Antmicro Ltd")
		(comment 1 "www.antmicro.com")
		(comment 9 "footprints 451-456 of 510")
	)
	(layers
		(0 "F.Cu" signal)
		(4 "In1.Cu" signal)
		(6 "In2.Cu" signal)
		(8 "In3.Cu" signal)
		(10 "In4.Cu" signal)
		(12 "In5.Cu" signal)
		(14 "In6.Cu" signal)
		(2 "B.Cu" signal)
		(9 "F.Adhes" user "F.Adhesive")
		(11 "B.Adhes" user "B.Adhesive")
		(13 "F.Paste" user)
		(15 "B.Paste" user)
		(5 "F.SilkS" user "F.Silkscreen")
		(7 "B.SilkS" user "B.Silkscreen")
		(1 "F.Mask" user)
		(3 "B.Mask" user)
		(17 "Dwgs.User" user "User.Drawings")
		(19 "Cmts.User" user "User.Comments")
		(21 "Eco1.User" user "User.Eco1")
		(23 "Eco2.User" user "User.Eco2")
		(25 "Edge.Cuts" user)
		(27 "Margin" user)
		(31 "F.CrtYd" user "F.Courtyard")
		(29 "B.CrtYd" user "B.Courtyard")
		(35 "F.Fab" user)
		(33 "B.Fab" user)
	)
	(footprint "antmicro-footprints:R_0402_1005Metric"
		(layer "B.Cu")
		(at 107.2 68.15 -90)
		(descr "Resistor SMD 0402")
		(tags "resistor SMD 0402")
		(property "Reference" "R163"
			(at -3.64 -0.44 90)
			(layer "B.SilkS")
			(effects
				(font
					(size 0.7 0.7)
					(thickness 0.15)
				)
				(justify left bottom mirror)
			)
		)
		(property "Value" "R_0R_0402"
			(at -1.011843 -1.772046 90)
			(layer "B.Fab")
			(hide yes)
			(effects
				(font
					(size 0.7 0.7)
					(thickness 0.15)
				)
				(justify left bottom mirror)
			)
		)
		(property "Datasheet" "https://industrial.panasonic.com/cdbs/www-data/pdf/RDA0000/AOA0000C301.pdf"
			(at 0 0 90)
			(layer "B.Fab")
			(hide yes)
			(effects
				(font
					(size 1.27 1.27)
					(thickness 0.15)
				)
				(justify mirror)
			)
		)
		(property "Description" "SMD Chip Resistor, Jumper, 0 ohm, 100 mW, 0402 [1005 Metric], Thick Film, General Purpose"
			(at 0 0 90)
			(layer "B.Fab")
			(hide yes)
			(effects
				(font
					(size 1.27 1.27)
					(thickness 0.15)
				)
				(justify mirror)
			)
		)
		(property "MPN" "ERJ2GE0R00X"
			(at 0 0 270)
			(unlocked yes)
			(layer "B.Fab")
			(hide yes)
			(effects
				(font
					(size 1 1)
					(thickness 0.15)
				)
				(justify mirror)
			)
		)
		(property "Manufacturer" "Panasonic"
			(at 0 0 270)
			(unlocked yes)
			(layer "B.Fab")
			(hide yes)
			(effects
				(font
					(size 1 1)
					(thickness 0.15)
				)
				(justify mirror)
			)
		)
		(property "License" "Apache-2.0"
			(at 0 0 270)
			(unlocked yes)
			(layer "B.Fab")
			(hide yes)
			(effects
				(font
					(size 1 1)
					(thickness 0.15)
				)
				(justify mirror)
			)
		)
		(property "Author" "Antmicro"
			(at 0 0 270)
			(unlocked yes)
			(layer "B.Fab")
			(hide yes)
			(effects
				(font
					(size 1 1)
					(thickness 0.15)
				)
				(justify mirror)
			)
		)
		(property "Val" "0R"
			(at 0 0 270)
			(unlocked yes)
			(layer "B.Fab")
			(hide yes)
			(effects
				(font
					(size 1 1)
					(thickness 0.15)
				)
				(justify mirror)
			)
		)
		(property "Tolerance" "~"
			(at 0 0 270)
			(unlocked yes)
			(layer "B.Fab")
			(hide yes)
			(effects
				(font
					(size 1 1)
					(thickness 0.15)
				)
				(justify mirror)
			)
		)
		(property "Current" "1A"
			(at 0 0 270)
			(unlocked yes)
			(layer "B.Fab")
			(hide yes)
			(effects
				(font
					(size 1 1)
					(thickness 0.15)
				)
				(justify mirror)
			)
		)
		(sheetname "/OCuLink/")
		(sheetfile "oculink.kicad_sch")
		(attr smd)
		(fp_rect
			(start -0.925 0.47)
			(end 0.925 -0.47)
			(stroke
				(width 0.05)
				(type default)
			)
			(fill no)
			(layer "B.CrtYd")
		)
		(fp_rect
			(start -0.5 0.25)
			(end 0.5 -0.25)
			(stroke
				(width 0.15)
				(type solid)
			)
			(fill no)
			(layer "B.Fab")
		)
		(pad "1" smd roundrect
			(at -0.48 0 270)
			(size 0.59 0.64)
			(layers "B.Cu" "B.Mask" "B.Paste")
			(roundrect_rratio 0.25)
			(net 226 "/OCuLink/SDA")
			(pintype "passive")
		)
		(pad "2" smd roundrect
			(at 0.48 0 270)
			(size 0.59 0.64)
			(layers "B.Cu" "B.Mask" "B.Paste")
			(roundrect_rratio 0.25)
			(net 395 "/OCuLink/SMBus.SDA")
			(pintype "passive")
		)
	)
	(footprint "antmicro-footprints:R_0402_1005Metric"
		(layer "B.Cu")
		(at 76.03 106.48)
		(descr "Resistor SMD 0402")
		(tags "resistor SMD 0402")
		(property "Reference" "R58"
			(at -2.72 0.72 0)
			(layer "B.SilkS")
			(effects
				(font
					(size 0.7 0.7)
					(thickness 0.15)
				)
				(justify right top mirror)
			)
		)
		(property "Value" "R_6k04_0.1%_0402"
			(at -1.011843 -1.772046 0)
			(layer "B.Fab")
			(hide yes)
			(effects
				(font
					(size 0.7 0.7)
					(thickness 0.15)
				)
				(justify right top mirror)
			)
		)
		(property "Datasheet" "https://www.vishay.com/docs/28758/tnpw_e3.pdf"
			(at 0 0 0)
			(layer "B.Fab")
			(hide yes)
			(effects
				(font
					(size 1.27 1.27)
					(thickness 0.15)
				)
				(justify mirror)
			)
		)
		(property "Description" "SMD Chip Resistor, 6.49 kohm, ± 1%, 62.5 mW, 0402 [1005 Metric], Thick Film, General Purpose"
			(at 0 0 0)
			(layer "B.Fab")
			(hide yes)
			(effects
				(font
					(size 1.27 1.27)
					(thickness 0.15)
				)
				(justify mirror)
			)
		)
		(property "MPN" "TNPW04026K04BEED"
			(at 0 0 0)
			(unlocked yes)
			(layer "B.Fab")
			(hide yes)
			(effects
				(font
					(size 1 1)
					(thickness 0.15)
				)
				(justify mirror)
			)
		)
		(property "Manufacturer" "Vishay"
			(at 0 0 0)
			(unlocked yes)
			(layer "B.Fab")
			(hide yes)
			(effects
				(font
					(size 1 1)
					(thickness 0.15)
				)
				(justify mirror)
			)
		)
		(property "License" "Apache-2.0"
			(at 0 0 0)
			(unlocked yes)
			(layer "B.Fab")
			(hide yes)
			(effects
				(font
					(size 1 1)
					(thickness 0.15)
				)
				(justify mirror)
			)
		)
		(property "Author" "Antmicro"
			(at 0 0 0)
			(unlocked yes)
			(layer "B.Fab")
			(hide yes)
			(effects
				(font
					(size 1 1)
					(thickness 0.15)
				)
				(justify mirror)
			)
		)
		(property "Val" "6k04"
			(at 0 0 0)
			(unlocked yes)
			(layer "B.Fab")
			(hide yes)
			(effects
				(font
					(size 1 1)
					(thickness 0.15)
				)
				(justify mirror)
			)
		)
		(property "Tolerance" "0.1%"
			(at 0 0 0)
			(unlocked yes)
			(layer "B.Fab")
			(hide yes)
			(effects
				(font
					(size 1 1)
					(thickness 0.15)
				)
				(justify mirror)
			)
		)
		(sheetname "/X710-AT2 10GbE/")
		(sheetfile "x710-at2-10gbe.kicad_sch")
		(attr smd)
		(fp_rect
			(start -0.925 0.47)
			(end 0.925 -0.47)
			(stroke
				(width 0.05)
				(type default)
			)
			(fill no)
			(layer "B.CrtYd")
		)
		(fp_rect
			(start -0.5 0.25)
			(end 0.5 -0.25)
			(stroke
				(width 0.15)
				(type solid)
			)
			(fill no)
			(layer "B.Fab")
		)
		(pad "1" smd roundrect
			(at -0.48 0)
			(size 0.59 0.64)
			(layers "B.Cu" "B.Mask" "B.Paste")
			(roundrect_rratio 0.25)
			(net 28 "GND")
			(pintype "passive")
		)
		(pad "2" smd roundrect
			(at 0.48 0)
			(size 0.59 0.64)
			(layers "B.Cu" "B.Mask" "B.Paste")
			(roundrect_rratio 0.25)
			(net 84 "/X710-AT2 10GbE/BIAS_RDAC")
			(pintype "passive")
		)
	)
	(footprint "antmicro-footprints:R_0402_1005Metric"
		(layer "B.Cu")
		(at 96.48 145.34 90)
		(descr "Resistor SMD 0402")
		(tags "resistor SMD 0402")
		(property "Reference" "R40"
			(at 0.75 -0.35 90)
			(layer "B.SilkS")
			(effects
				(font
					(size 0.7 0.7)
					(thickness 0.15)
				)
				(justify right top mirror)
			)
		)
		(property "Value" "R_220R_0402"
			(at -1.011843 -1.772046 90)
			(layer "B.Fab")
			(hide yes)
			(effects
				(font
					(size 0.7 0.7)
					(thickness 0.15)
				)
				(justify right top mirror)
			)
		)
		(property "Datasheet" "https://www.bourns.com/docs/product-datasheets/cr.pdf"
			(at 0 0 90)
			(layer "B.Fab")
			(hide yes)
			(effects
				(font
					(size 1.27 1.27)
					(thickness 0.15)
				)
				(justify mirror)
			)
		)
		(property "Description" "SMD Chip Resistor, 220 ohm, ± 1%, 62.5 mW, 0402 [1005 Metric], Thick Film, General Purpose"
			(at 0 0 90)
			(layer "B.Fab")
			(hide yes)
			(effects
				(font
					(size 1.27 1.27)
					(thickness 0.15)
				)
				(justify mirror)
			)
		)
		(property "MPN" "CR0402-FX-2200GLF"
			(at 0 0 90)
			(unlocked yes)
			(layer "B.Fab")
			(hide yes)
			(effects
				(font
					(size 1 1)
					(thickness 0.15)
				)
				(justify mirror)
			)
		)
		(property "Manufacturer" "Bourns"
			(at 0 0 90)
			(unlocked yes)
			(layer "B.Fab")
			(hide yes)
			(effects
				(font
					(size 1 1)
					(thickness 0.15)
				)
				(justify mirror)
			)
		)
		(property "License" "Apache-2.0"
			(at 0 0 90)
			(unlocked yes)
			(layer "B.Fab")
			(hide yes)
			(effects
				(font
					(size 1 1)
					(thickness 0.15)
				)
				(justify mirror)
			)
		)
		(property "Author" "Antmicro"
			(at 0 0 90)
			(unlocked yes)
			(layer "B.Fab")
			(hide yes)
			(effects
				(font
					(size 1 1)
					(thickness 0.15)
				)
				(justify mirror)
			)
		)
		(property "Val" "220R"
			(at 0 0 90)
			(unlocked yes)
			(layer "B.Fab")
			(hide yes)
			(effects
				(font
					(size 1 1)
					(thickness 0.15)
				)
				(justify mirror)
			)
		)
		(property "Tolerance" "1%"
			(at 0 0 90)
			(unlocked yes)
			(layer "B.Fab")
			(hide yes)
			(effects
				(font
					(size 1 1)
					(thickness 0.15)
				)
				(justify mirror)
			)
		)
		(sheetname "/2xRJ45/")
		(sheetfile "2xrj45.kicad_sch")
		(attr smd)
		(fp_rect
			(start -0.925 0.47)
			(end 0.925 -0.47)
			(stroke
				(width 0.05)
				(type default)
			)
			(fill no)
			(layer "B.CrtYd")
		)
		(fp_rect
			(start -0.5 0.25)
			(end 0.5 -0.25)
			(stroke
				(width 0.15)
				(type solid)
			)
			(fill no)
			(layer "B.Fab")
		)
		(pad "1" smd roundrect
			(at -0.48 0 90)
			(size 0.59 0.64)
			(layers "B.Cu" "B.Mask" "B.Paste")
			(roundrect_rratio 0.25)
			(net 64 "Net-(J6-LED_YG_G-)")
			(pintype "passive")
		)
		(pad "2" smd roundrect
			(at 0.48 0 90)
			(size 0.59 0.64)
			(layers "B.Cu" "B.Mask" "B.Paste")
			(roundrect_rratio 0.25)
			(net 87 "/2xRJ45/~{P1_LED_LINK_10G}")
			(pintype "passive")
		)
	)
	(footprint "antmicro-footprints:C_0402_1005Metric"
		(layer "B.Cu")
		(at 78.88 106.48 180)
		(descr "Capacitor SMD 0402")
		(tags "capacitor SMD 0402")
		(property "Reference" "C141"
			(at -1.52 -11.29 0)
			(layer "B.SilkS")
			(effects
				(font
					(size 0.7 0.7)
					(thickness 0.15)
				)
				(justify left bottom mirror)
			)
		)
		(property "Value" "C_1u_25V_0402"
			(at -1.022927 -2.155213 0)
			(layer "B.Fab")
			(hide yes)
			(effects
				(font
					(size 0.7 0.7)
					(thickness 0.15)
				)
				(justify left bottom mirror)
			)
		)
		(property "Datasheet" "https://www.murata.com/products/productdetail?partno=GRM155R61E105KE11%23"
			(at 0 0 0)
			(layer "B.Fab")
			(hide yes)
			(effects
				(font
					(size 1.27 1.27)
					(thickness 0.15)
				)
				(justify mirror)
			)
		)
		(property "Description" "SMD Multilayer Ceramic Capacitor, 1 µF, 25 V, 0402 [1005 Metric], ± 10%, X5R, GRM Series"
			(at 0 0 0)
			(layer "B.Fab")
			(hide yes)
			(effects
				(font
					(size 1.27 1.27)
					(thickness 0.15)
				)
				(justify mirror)
			)
		)
		(property "MPN" "GRM155R61E105KE11J"
			(at 0 0 180)
			(unlocked yes)
			(layer "B.Fab")
			(hide yes)
			(effects
				(font
					(size 1 1)
					(thickness 0.15)
				)
				(justify mirror)
			)
		)
		(property "Manufacturer" "Murata"
			(at 0 0 180)
			(unlocked yes)
			(layer "B.Fab")
			(hide yes)
			(effects
				(font
					(size 1 1)
					(thickness 0.15)
				)
				(justify mirror)
			)
		)
		(property "License" "Apache-2.0"
			(at 0 0 180)
			(unlocked yes)
			(layer "B.Fab")
			(hide yes)
			(effects
				(font
					(size 1 1)
					(thickness 0.15)
				)
				(justify mirror)
			)
		)
		(property "Author" "Antmicro"
			(at 0 0 180)
			(unlocked yes)
			(layer "B.Fab")
			(hide yes)
			(effects
				(font
					(size 1 1)
					(thickness 0.15)
				)
				(justify mirror)
			)
		)
		(property "Val" "1u"
			(at 0 0 180)
			(unlocked yes)
			(layer "B.Fab")
			(hide yes)
			(effects
				(font
					(size 1 1)
					(thickness 0.15)
				)
				(justify mirror)
			)
		)
		(property "Voltage" "25V"
			(at 0 0 180)
			(unlocked yes)
			(layer "B.Fab")
			(hide yes)
			(effects
				(font
					(size 1 1)
					(thickness 0.15)
				)
				(justify mirror)
			)
		)
		(property "Dielectric" "X5R"
			(at 0 0 180)
			(unlocked yes)
			(layer "B.Fab")
			(hide yes)
			(effects
				(font
					(size 1 1)
					(thickness 0.15)
				)
				(justify mirror)
			)
		)
		(sheetname "/X710-AT2 power/")
		(sheetfile "x710-at2-power.kicad_sch")
		(attr smd)
		(fp_rect
			(start -0.925 0.47)
			(end 0.925 -0.47)
			(stroke
				(width 0.05)
				(type default)
			)
			(fill no)
			(layer "B.CrtYd")
		)
		(fp_line
			(start 0.504 0.25)
			(end 0.504 -0.248)
			(stroke
				(width 0.15)
				(type solid)
			)
			(layer "B.Fab")
		)
		(fp_line
			(start 0.504 -0.248)
			(end -0.494 -0.248)
			(stroke
				(width 0.15)
				(type solid)
			)
			(layer "B.Fab")
		)
		(fp_line
			(start -0.494 0.25)
			(end 0.504 0.25)
			(stroke
				(width 0.15)
				(type solid)
			)
			(layer "B.Fab")
		)
		(fp_line
			(start -0.494 -0.248)
			(end -0.494 0.25)
			(stroke
				(width 0.15)
				(type solid)
			)
			(layer "B.Fab")
		)
		(pad "1" smd roundrect
			(at -0.48 0 180)
			(size 0.59 0.64)
			(layers "B.Cu" "B.Mask" "B.Paste")
			(roundrect_rratio 0.25)
			(net 28 "GND")
			(pintype "passive")
		)
		(pad "2" smd roundrect
			(at 0.48 0 180)
			(size 0.59 0.64)
			(layers "B.Cu" "B.Mask" "B.Paste")
			(roundrect_rratio 0.25)
			(net 10 "AVDDH")
			(pintype "passive")
		)
	)
	(footprint "antmicro-footprints:R_0402_1005Metric"
		(layer "B.Cu")
		(at 93.225 94 -90)
		(descr "Resistor SMD 0402")
		(tags "resistor SMD 0402")
		(property "Reference" "R136"
			(at -1.38 -0.575 90)
			(layer "B.SilkS")
			(effects
				(font
					(size 0.7 0.7)
					(thickness 0.15)
				)
				(justify left top mirror)
			)
		)
		(property "Value" "R_100R_0402"
			(at -1.011843 -1.772046 90)
			(layer "B.Fab")
			(hide yes)
			(effects
				(font
					(size 0.7 0.7)
					(thickness 0.15)
				)
				(justify left bottom mirror)
			)
		)
		(property "Datasheet" "https://www.bourns.com/docs/product-datasheets/cr.pdf"
			(at 0 0 90)
			(layer "B.Fab")
			(hide yes)
			(effects
				(font
					(size 1.27 1.27)
					(thickness 0.15)
				)
				(justify mirror)
			)
		)
		(property "Description" "SMD Chip Resistor, 100 ohm, ± 1%, 62.5 mW, 0402 [1005 Metric], Thick Film, General Purpose"
			(at 0 0 90)
			(layer "B.Fab")
			(hide yes)
			(effects
				(font
					(size 1.27 1.27)
					(thickness 0.15)
				)
				(justify mirror)
			)
		)
		(property "MPN" "CR0402-FX-1000GLF"
			(at 0 0 270)
			(unlocked yes)
			(layer "B.Fab")
			(hide yes)
			(effects
				(font
					(size 1 1)
					(thickness 0.15)
				)
				(justify mirror)
			)
		)
		(property "Manufacturer" "Bourns"
			(at 0 0 270)
			(unlocked yes)
			(layer "B.Fab")
			(hide yes)
			(effects
				(font
					(size 1 1)
					(thickness 0.15)
				)
				(justify mirror)
			)
		)
		(property "License" "Apache-2.0"
			(at 0 0 270)
			(unlocked yes)
			(layer "B.Fab")
			(hide yes)
			(effects
				(font
					(size 1 1)
					(thickness 0.15)
				)
				(justify mirror)
			)
		)
		(property "Author" "Antmicro"
			(at 0 0 270)
			(unlocked yes)
			(layer "B.Fab")
			(hide yes)
			(effects
				(font
					(size 1 1)
					(thickness 0.15)
				)
				(justify mirror)
			)
		)
		(property "Val" "100R"
			(at 0 0 270)
			(unlocked yes)
			(layer "B.Fab")
			(hide yes)
			(effects
				(font
					(size 1 1)
					(thickness 0.15)
				)
				(justify mirror)
			)
		)
		(property "Tolerance" "1%"
			(at 0 0 270)
			(unlocked yes)
			(layer "B.Fab")
			(hide yes)
			(effects
				(font
					(size 1 1)
					(thickness 0.15)
				)
				(justify mirror)
			)
		)
		(sheetname "/X710-AT2 RSVD/")
		(sheetfile "x710-at2-rsvd.kicad_sch")
		(attr smd)
		(fp_rect
			(start -0.925 0.47)
			(end 0.925 -0.47)
			(stroke
				(width 0.05)
				(type default)
			)
			(fill no)
			(layer "B.CrtYd")
		)
		(fp_rect
			(start -0.5 0.25)
			(end 0.5 -0.25)
			(stroke
				(width 0.15)
				(type solid)
			)
			(fill no)
			(layer "B.Fab")
		)
		(pad "1" smd roundrect
			(at -0.48 0 270)
			(size 0.59 0.64)
			(layers "B.Cu" "B.Mask" "B.Paste")
			(roundrect_rratio 0.25)
			(net 28 "GND")
			(pintype "passive")
		)
		(pad "2" smd roundrect
			(at 0.48 0 270)
			(size 0.59 0.64)
			(layers "B.Cu" "B.Mask" "B.Paste")
			(roundrect_rratio 0.25)
			(net 124 "/X710-AT2 RSVD/RSVDW5_VSS")
			(pintype "passive")
		)
	)
	(footprint "antmicro-footprints:C_0402_1005Metric"
		(layer "B.Cu")
		(at 106.635 92.32 90)
		(descr "Capacitor SMD 0402")
		(tags "capacitor SMD 0402")
		(property "Reference" "C76"
			(at -0.85 0.585 90)
			(layer "B.SilkS")
			(effects
				(font
					(size 0.7 0.7)
					(thickness 0.15)
				)
				(justify right top mirror)
			)
		)
		(property "Value" "C_100n_0402"
			(at -1.022927 -2.155213 90)
			(layer "B.Fab")
			(hide yes)
			(effects
				(font
					(size 0.7 0.7)
					(thickness 0.15)
				)
				(justify right top mirror)
			)
		)
		(property "Datasheet" "https://www.murata.com/products/productdetail?partno=GRM155R61H104KE14%23"
			(at 0 0 90)
			(layer "B.Fab")
			(hide yes)
			(effects
				(font
					(size 1.27 1.27)
					(thickness 0.15)
				)
				(justify mirror)
			)
		)
		(property "Description" "SMD Multilayer Ceramic Capacitor, 0.1 µF, 50 V, 0402 [1005 Metric], ± 10%, X5R, GRM Series"
			(at 0 0 90)
			(layer "B.Fab")
			(hide yes)
			(effects
				(font
					(size 1.27 1.27)
					(thickness 0.15)
				)
				(justify mirror)
			)
		)
		(property "MPN" "GRM155R61H104KE14D"
			(at 0 0 90)
			(unlocked yes)
			(layer "B.Fab")
			(hide yes)
			(effects
				(font
					(size 1 1)
					(thickness 0.15)
				)
				(justify mirror)
			)
		)
		(property "Val" "100n"
			(at 0 0 90)
			(unlocked yes)
			(layer "B.Fab")
			(hide yes)
			(effects
				(font
					(size 1 1)
					(thickness 0.15)
				)
				(justify mirror)
			)
		)
		(property "Voltage" "50V"
			(at 0 0 90)
			(unlocked yes)
			(layer "B.Fab")
			(hide yes)
			(effects
				(font
					(size 1 1)
					(thickness 0.15)
				)
				(justify mirror)
			)
		)
		(property "Dielectric" "X5R"
			(at 0 0 90)
			(unlocked yes)
			(layer "B.Fab")
			(hide yes)
			(effects
				(font
					(size 1 1)
					(thickness 0.15)
				)
				(justify mirror)
			)
		)
		(property "Manufacturer" "Murata"
			(at 0 0 90)
			(unlocked yes)
			(layer "B.Fab")
			(hide yes)
			(effects
				(font
					(size 1 1)
					(thickness 0.15)
				)
				(justify mirror)
			)
		)
		(property "License" "Apache-2.0"
			(at 0 0 90)
			(unlocked yes)
			(layer "B.Fab")
			(hide yes)
			(effects
				(font
					(size 1 1)
					(thickness 0.15)
				)
				(justify mirror)
			)
		)
		(property "Author" "Antmicro"
			(at 0 0 90)
			(unlocked yes)
			(layer "B.Fab")
			(hide yes)
			(effects
				(font
					(size 1 1)
					(thickness 0.15)
				)
				(justify mirror)
			)
		)
		(sheetname "/X710-AT2 Misc/")
		(sheetfile "x710-at2-mics.kicad_sch")
		(attr smd)
		(fp_rect
			(start -0.925 0.47)
			(end 0.925 -0.47)
			(stroke
				(width 0.05)
				(type default)
			)
			(fill no)
			(layer "B.CrtYd")
		)
		(fp_line
			(start 0.504 -0.248)
			(end -0.494 -0.248)
			(stroke
				(width 0.15)
				(type solid)
			)
			(layer "B.Fab")
		)
		(fp_line
			(start -0.494 -0.248)
			(end -0.494 0.25)
			(stroke
				(width 0.15)
				(type solid)
			)
			(layer "B.Fab")
		)
		(fp_line
			(start 0.504 0.25)
			(end 0.504 -0.248)
			(stroke
				(width 0.15)
				(type solid)
			)
			(layer "B.Fab")
		)
		(fp_line
			(start -0.494 0.25)
			(end 0.504 0.25)
			(stroke
				(width 0.15)
				(type solid)
			)
			(layer "B.Fab")
		)
		(pad "1" smd roundrect
			(at -0.48 0 90)
			(size 0.59 0.64)
			(layers "B.Cu" "B.Mask" "B.Paste")
			(roundrect_rratio 0.25)
			(net 28 "GND")
			(pintype "passive")
		)
		(pad "2" smd roundrect
			(at 0.48 0 90)
			(size 0.59 0.64)
			(layers "B.Cu" "B.Mask" "B.Paste")
			(roundrect_rratio 0.25)
			(net 18 "+1V88")
			(pintype "passive")
		)
	)
)
